# T6G (Grand Teton) — schematic netlist excerpt (pin names and nets, part order shuffled) for the footprints in the layout excerpt that follows; sources: Cadence DE-HDL packaged netlist, KiCad conversion of 04192023_DAF0TMB3IC0_F0TG_MB_C_brd_V02_OCP.brd

C863  Q_CAP_DIFFBUS  DIFF BUS_0.22UF 6.3V 20% X6S  pkg C0201  page 64 : \1\ = P5E_CPU0_P2_TX_C_DP<3> ; \2\ = P5E_CPU0_P2_TX_DP<3>
R2940  Q_RES  4.7K 5% EMPTY  pkg 0402LF  page 241 : A = P3V3_AUX ; B = FM_GPU_HSC_EN
R1638  Q_RES  22 1% CHIP  pkg 0402LF  page 173 : A = JTAG_P0_R_TCK ; B = JTAG_CPU0_TCK

(kicad_pcb
	(version 20260206)
	(generator "pcbnew")
	(generator_version "10.0")
	(general
		(thickness 1.6)
		(legacy_teardrops no)
	)
	(paper "A4")
	(title_block
		(title "04192023_DAF0TMB3IC0_F0TG_MB_C_brd_V02_OCP.brd")
		(comment 1 "Grand Teton / footprints 2630-2632 of 8354")
	)
	(layers
		(0 "F.Cu" signal "TOP")
		(4 "In1.Cu" signal "GND")
		(6 "In2.Cu" signal "IN1")
		(8 "In3.Cu" signal "GND1")
		(10 "In4.Cu" signal "IN2")
		(12 "In5.Cu" signal "GND2")
		(14 "In6.Cu" signal "IN3")
		(16 "In7.Cu" signal "GND3")
		(18 "In8.Cu" signal "VCC")
		(20 "In9.Cu" signal "VCC1")
		(22 "In10.Cu" signal "GND4")
		(24 "In11.Cu" signal "IN4")
		(26 "In12.Cu" signal "GND5")
		(28 "In13.Cu" signal "IN5")
		(30 "In14.Cu" signal "GND6")
		(32 "In15.Cu" signal "IN6")
		(34 "In16.Cu" signal "GND7")
		(2 "B.Cu" signal "BOTTOM")
		(9 "F.Adhes" user "F.Adhesive")
		(11 "B.Adhes" user "B.Adhesive")
		(13 "F.Paste" user "Package Geometry/Pastemask Top")
		(15 "B.Paste" user "Package Geometry/Pastemask Bottom")
		(5 "F.SilkS" user "Ref Des/Silkscreen Top")
		(7 "B.SilkS" user "Ref Des/Silkscreen Bottom")
		(1 "F.Mask" user "Board Geometry/Soldermask Top")
		(3 "B.Mask" user "Board Geometry/Soldermask Bottom")
		(17 "Dwgs.User" user "User.Drawings")
		(19 "Cmts.User" user "User.Comments")
		(21 "Eco1.User" user "User.Eco1")
		(23 "Eco2.User" user "User.Eco2")
		(25 "Edge.Cuts" user "Board Geometry/Outline")
		(27 "Margin" user)
		(31 "F.CrtYd" user "Package Geometry/Place Bound Top")
		(29 "B.CrtYd" user "Package Geometry/Place Bound Bottom")
		(35 "F.Fab" user "Ref Des/Assembly Top")
		(33 "B.Fab" user "Ref Des/Assembly Bottom")
	)
	(footprint ""
		(layer "F.Cu")
		(at 192.47358 -413.964882 90)
		(property "Reference" "R2940"
			(at 0 0 90)
			(layer "F.SilkS")
			(hide yes)
			(effects
				(font
					(size 1.27 1.27)
				)
			)
		)
		(property "Value" ""
			(at 0 0 90)
			(layer "F.Fab")
			(effects
				(font
					(size 1.27 1.27)
				)
			)
		)
		(duplicate_pad_numbers_are_jumpers no)
		(fp_line
			(start 0.7874 -0.4064)
			(end 0.7874 0.4064)
			(stroke
				(width 0.1524)
				(type default)
			)
			(layer "F.SilkS")
		)
		(fp_line
			(start -0.7874 -0.4064)
			(end 0.7874 -0.4064)
			(stroke
				(width 0.1524)
				(type default)
			)
			(layer "F.SilkS")
		)
		(fp_line
			(start 0.7874 0.4064)
			(end -0.7874 0.4064)
			(stroke
				(width 0.1524)
				(type default)
			)
			(layer "F.SilkS")
		)
		(fp_line
			(start -0.7874 0.4064)
			(end -0.7874 -0.4064)
			(stroke
				(width 0.1524)
				(type default)
			)
			(layer "F.SilkS")
		)
		(fp_line
			(start -0.12065 -0.305054)
			(end -0.12065 -0.2794)
			(stroke
				(width 0.1)
				(type default)
			)
			(layer "F.Fab")
		)
		(fp_line
			(start -0.67945 -0.305054)
			(end -0.12065 -0.305054)
			(stroke
				(width 0.1)
				(type default)
			)
			(layer "F.Fab")
		)
		(fp_line
			(start 0.67945 -0.3048)
			(end 0.67945 0.3048)
			(stroke
				(width 0.1)
				(type default)
			)
			(layer "F.Fab")
		)
		(fp_line
			(start 0.12065 -0.3048)
			(end 0.67945 -0.3048)
			(stroke
				(width 0.1)
				(type default)
			)
			(layer "F.Fab")
		)
		(fp_line
			(start 0.12065 -0.2794)
			(end 0.12065 -0.3048)
			(stroke
				(width 0.1)
				(type default)
			)
			(layer "F.Fab")
		)
		(fp_line
			(start -0.12065 -0.2794)
			(end 0.12065 -0.2794)
			(stroke
				(width 0.1)
				(type default)
			)
			(layer "F.Fab")
		)
		(fp_line
			(start 0.120396 0.2794)
			(end -0.12065 0.2794)
			(stroke
				(width 0.1)
				(type default)
			)
			(layer "F.Fab")
		)
		(fp_line
			(start -0.12065 0.2794)
			(end -0.12065 0.3048)
			(stroke
				(width 0.1)
				(type default)
			)
			(layer "F.Fab")
		)
		(fp_line
			(start 0.67945 0.3048)
			(end 0.120396 0.3048)
			(stroke
				(width 0.1)
				(type default)
			)
			(layer "F.Fab")
		)
		(fp_line
			(start 0.120396 0.3048)
			(end 0.120396 0.2794)
			(stroke
				(width 0.1)
				(type default)
			)
			(layer "F.Fab")
		)
		(fp_line
			(start -0.12065 0.3048)
			(end -0.67945 0.3048)
			(stroke
				(width 0.1)
				(type default)
			)
			(layer "F.Fab")
		)
		(fp_line
			(start -0.67945 0.3048)
			(end -0.67945 -0.305054)
			(stroke
				(width 0.1)
				(type default)
			)
			(layer "F.Fab")
		)
		(pad "1" smd circle
			(at -0.40005 0 90)
			(size 0 0)
			(layers "F.Cu" "F.Mask" "F.Paste")
			(net "P3V3_AUX")
		)
		(pad "2" smd circle
			(at 0.40005 0 90)
			(size 0 0)
			(layers "F.Cu" "F.Mask" "F.Paste")
			(net "FM_GPU_HSC_EN")
		)
	)
	(footprint ""
		(layer "F.Cu")
		(at 400.31924 -378.95403 -90)
		(property "Reference" "C863"
			(at 0 0 270)
			(layer "F.SilkS")
			(hide yes)
			(effects
				(font
					(size 1.27 1.27)
				)
			)
		)
		(property "Value" ""
			(at 0 0 270)
			(layer "F.Fab")
			(effects
				(font
					(size 1.27 1.27)
				)
			)
		)
		(duplicate_pad_numbers_are_jumpers no)
		(fp_line
			(start -0.299974 0.150114)
			(end -0.299974 -0.150114)
			(stroke
				(width 0.1)
				(type default)
			)
			(layer "F.Fab")
		)
		(fp_line
			(start 0.299974 0.150114)
			(end -0.299974 0.150114)
			(stroke
				(width 0.1)
				(type default)
			)
			(layer "F.Fab")
		)
		(fp_line
			(start -0.299974 -0.150114)
			(end 0.299974 -0.150114)
			(stroke
				(width 0.1)
				(type default)
			)
			(layer "F.Fab")
		)
		(fp_line
			(start 0.299974 -0.150114)
			(end 0.299974 0.150114)
			(stroke
				(width 0.1)
				(type default)
			)
			(layer "F.Fab")
		)
		(pad "1" smd rect
			(at -0.2667 0 270)
			(size 0.3048 0.381)
			(layers "F.Cu" "F.Mask" "F.Paste")
			(net "P5E_CPU0_P2_TX_C_DP<3>")
		)
		(pad "2" smd rect
			(at 0.2667 0 270)
			(size 0.3048 0.381)
			(layers "F.Cu" "F.Mask" "F.Paste")
			(net "P5E_CPU0_P2_TX_DP<3>")
		)
	)
	(footprint ""
		(layer "F.Cu")
		(at 254.11684 -92.719144 -90)
		(property "Reference" "R1638"
			(at 0 0 270)
			(layer "F.SilkS")
			(hide yes)
			(effects
				(font
					(size 1.27 1.27)
				)
			)
		)
		(property "Value" ""
			(at 0 0 270)
			(layer "F.Fab")
			(effects
				(font
					(size 1.27 1.27)
				)
			)
		)
		(duplicate_pad_numbers_are_jumpers no)
		(fp_line
			(start -0.7874 0.4064)
			(end -0.7874 -0.4064)
			(stroke
				(width 0.1524)
				(type default)
			)
			(layer "F.SilkS")
		)
		(fp_line
			(start 0.7874 0.4064)
			(end -0.7874 0.4064)
			(stroke
				(width 0.1524)
				(type default)
			)
			(layer "F.SilkS")
		)
		(fp_line
			(start -0.7874 -0.4064)
			(end 0.7874 -0.4064)
			(stroke
				(width 0.1524)
				(type default)
			)
			(layer "F.SilkS")
		)
		(fp_line
			(start 0.7874 -0.4064)
			(end 0.7874 0.4064)
			(stroke
				(width 0.1524)
				(type default)
			)
			(layer "F.SilkS")
		)
		(fp_line
			(start -0.67945 0.3048)
			(end -0.67945 -0.305054)
			(stroke
				(width 0.1)
				(type default)
			)
			(layer "F.Fab")
		)
		(fp_line
			(start -0.12065 0.3048)
			(end -0.67945 0.3048)
			(stroke
				(width 0.1)
				(type default)
			)
			(layer "F.Fab")
		)
		(fp_line
			(start 0.120396 0.3048)
			(end 0.120396 0.2794)
			(stroke
				(width 0.1)
				(type default)
			)
			(layer "F.Fab")
		)
		(fp_line
			(start 0.67945 0.3048)
			(end 0.120396 0.3048)
			(stroke
				(width 0.1)
				(type default)
			)
			(layer "F.Fab")
		)
		(fp_line
			(start -0.12065 0.2794)
			(end -0.12065 0.3048)
			(stroke
				(width 0.1)
				(type default)
			)
			(layer "F.Fab")
		)
		(fp_line
			(start 0.120396 0.2794)
			(end -0.12065 0.2794)
			(stroke
				(width 0.1)
				(type default)
			)
			(layer "F.Fab")
		)
		(fp_line
			(start -0.12065 -0.2794)
			(end 0.12065 -0.2794)
			(stroke
				(width 0.1)
				(type default)
			)
			(layer "F.Fab")
		)
		(fp_line
			(start 0.12065 -0.2794)
			(end 0.12065 -0.3048)
			(stroke
				(width 0.1)
				(type default)
			)
			(layer "F.Fab")
		)
		(fp_line
			(start 0.12065 -0.3048)
			(end 0.67945 -0.3048)
			(stroke
				(width 0.1)
				(type default)
			)
			(layer "F.Fab")
		)
		(fp_line
			(start 0.67945 -0.3048)
			(end 0.67945 0.3048)
			(stroke
				(width 0.1)
				(type default)
			)
			(layer "F.Fab")
		)
		(fp_line
			(start -0.67945 -0.305054)
			(end -0.12065 -0.305054)
			(stroke
				(width 0.1)
				(type default)
			)
			(layer "F.Fab")
		)
		(fp_line
			(start -0.12065 -0.305054)
			(end -0.12065 -0.2794)
			(stroke
				(width 0.1)
				(type default)
			)
			(layer "F.Fab")
		)
		(pad "1" smd circle
			(at -0.40005 0 270)
			(size 0 0)
			(layers "F.Cu" "F.Mask" "F.Paste")
			(net "JTAG_P0_R_TCK")
		)
		(pad "2" smd circle
			(at 0.40005 0 270)
			(size 0 0)
			(layers "F.Cu" "F.Mask" "F.Paste")
			(net "JTAG_CPU0_TCK")
		)
	)
)
